# TIMECARD (Time Appliance Project (Time Card)) — schematic netlist excerpt (pin names and nets, part order shuffled) for the footprints in the layout excerpt that follows; sources: Cadence DE-HDL packaged netlist, KiCad conversion of R4006-B0001-02_R01.brd

R65  RESISTOR  4.7KOHM 1%  pkg SMC_0402R_H016  page 18 : \1\ = XP3R3V_FPGA ; \2\ = SHT3X_I2C_SCL
R337  RESISTOR  4.7KOHM 1%  pkg SMC_0402R_H016  page 17 : \1\ = XP3R3V_FPGA ; \2\ = UNNAMED_6_LM75BDPTSSOP8_I34_A0

(kicad_pcb
	(version 20260206)
	(generator "pcbnew")
	(generator_version "10.0")
	(general
		(thickness 1.6)
		(legacy_teardrops no)
	)
	(paper "A4")
	(title_block
		(title "timecard-production-celestica-r4006 — R4006-B0001-02_R01.brd")
		(comment 1 "Time Appliance Project (Time Card) / footprints 845-846 of 1113")
	)
	(layers
		(0 "F.Cu" signal "TOP")
		(4 "In1.Cu" signal "L02_GND1")
		(6 "In2.Cu" signal "L03_SIG1")
		(8 "In3.Cu" signal "L04_GND2")
		(10 "In4.Cu" signal "L05_VCC1")
		(12 "In5.Cu" signal "L06_VCC2")
		(14 "In6.Cu" signal "L07_GND3")
		(16 "In7.Cu" signal "L08_SIG2")
		(18 "In8.Cu" signal "L09_GND4")
		(2 "B.Cu" signal "BOTTOM")
		(9 "F.Adhes" user "F.Adhesive")
		(11 "B.Adhes" user "B.Adhesive")
		(13 "F.Paste" user "Package Geometry/Pastemask Top")
		(15 "B.Paste" user "Package Geometry/Pastemask Bottom")
		(5 "F.SilkS" user "Ref Des/Silkscreen Top")
		(7 "B.SilkS" user "Ref Des/Silkscreen Bottom")
		(1 "F.Mask" user "Board Geometry/Soldermask Top")
		(3 "B.Mask" user "Board Geometry/Soldermask Bottom")
		(17 "Dwgs.User" user "User.Drawings")
		(19 "Cmts.User" user "User.Comments")
		(21 "Eco1.User" user "User.Eco1")
		(23 "Eco2.User" user "User.Eco2")
		(25 "Edge.Cuts" user "Board Geometry/Outline")
		(27 "Margin" user)
		(31 "F.CrtYd" user "Package Geometry/Place Bound Top")
		(29 "B.CrtYd" user "Package Geometry/Place Bound Bottom")
		(35 "F.Fab" user "Ref Des/Assembly Top")
		(33 "B.Fab" user "Ref Des/Assembly Bottom")
	)
	(footprint ""
		(layer "B.Cu")
		(at 5.588 -75.565 180)
		(property "Reference" "R337"
			(at 3.048 0.59563 0)
			(unlocked yes)
			(layer "B.SilkS")
			(effects
				(font
					(size 0.7874 0.5842)
					(thickness 0.1524)
				)
				(justify mirror)
			)
		)
		(property "Value" "VAL*"
			(at -0.02032 2.13233 180)
			(unlocked yes)
			(layer "B.Fab")
			(hide yes)
			(effects
				(font
					(size 0.7874 0.5842)
					(thickness 0.1524)
				)
				(justify mirror)
			)
		)
		(property "Tolerance" "TOL*"
			(at -0.044704 3.05435 180)
			(unlocked yes)
			(layer "Cmts.User")
			(hide yes)
			(effects
				(font
					(size 0.7874 0.5842)
					(thickness 0.1524)
				)
				(justify mirror)
			)
		)
		(property "User Part Number" "PARTNUM*"
			(at -0.02032 4.024884 180)
			(unlocked yes)
			(layer "Cmts.User")
			(hide yes)
			(effects
				(font
					(size 0.7874 0.5842)
					(thickness 0.1524)
				)
				(justify mirror)
			)
		)
		(property "Device Type" "RESISTOR-G155-14701-01,4.7KOHMA"
			(at -0.008382 1.210564 180)
			(unlocked yes)
			(layer "B.Fab")
			(hide yes)
			(effects
				(font
					(size 0.7874 0.5842)
					(thickness 0.1524)
				)
				(justify mirror)
			)
		)
		(duplicate_pad_numbers_are_jumpers no)
		(fp_line
			(start 1.143 0.5588)
			(end -1.143 0.5588)
			(stroke
				(width 0.1)
				(type default)
			)
			(layer "B.SilkS")
		)
		(fp_line
			(start 1.143 -0.5588)
			(end 1.143 0.5588)
			(stroke
				(width 0.1)
				(type default)
			)
			(layer "B.SilkS")
		)
		(fp_line
			(start -1.143 0.5588)
			(end -1.143 -0.5588)
			(stroke
				(width 0.1)
				(type default)
			)
			(layer "B.SilkS")
		)
		(fp_line
			(start -1.143 -0.5588)
			(end 1.143 -0.5588)
			(stroke
				(width 0.1)
				(type default)
			)
			(layer "B.SilkS")
		)
		(fp_rect
			(start -1.143 0.5588)
			(end 1.143 -0.5588)
			(stroke
				(width 0)
				(type default)
			)
			(fill no)
			(layer "B.CrtYd")
		)
		(fp_line
			(start 0.508 0.3048)
			(end -0.508 0.3048)
			(stroke
				(width 0.1)
				(type default)
			)
			(layer "B.Fab")
		)
		(fp_line
			(start 0.508 -0.3048)
			(end 0.508 0.3048)
			(stroke
				(width 0.1)
				(type default)
			)
			(layer "B.Fab")
		)
		(fp_line
			(start -0.508 0.3048)
			(end -0.508 -0.3048)
			(stroke
				(width 0.1)
				(type default)
			)
			(layer "B.Fab")
		)
		(fp_line
			(start -0.508 -0.3048)
			(end 0.508 -0.3048)
			(stroke
				(width 0.1)
				(type default)
			)
			(layer "B.Fab")
		)
		(pad "1" smd rect
			(at 0.5334 0)
			(size 0.7112 0.6096)
			(layers "B.Cu" "B.Mask" "B.Paste")
			(net "XP3R3V_FPGA")
		)
		(pad "2" smd rect
			(at -0.5334 0)
			(size 0.7112 0.6096)
			(layers "B.Cu" "B.Mask" "B.Paste")
			(net "UNNAMED_6_LM75BDPTSSOP8_I34_A0")
		)
		(zone
			(layer "B.Cu")
			(hatch none 0.5)
			(connect_pads
				(clearance 0)
			)
			(min_thickness 0.25)
			(keepout
				(tracks allowed)
				(vias not_allowed)
				(pads allowed)
				(copperpour not_allowed)
				(footprints allowed)
			)
			(placement
				(enabled no)
				(sheetname "")
			)
			(fill
				(thermal_gap 0.5)
				(thermal_bridge_width 0.5)
				(island_removal_mode 0)
			)
			(polygon
				(pts
					(xy 5.6642 -75.8698) (xy 5.5118 -75.8698) (xy 5.5118 -75.2602) (xy 5.6642 -75.2602)
				)
			)
		)
	)
	(footprint ""
		(layer "B.Cu")
		(at 154.153108 -49.01311 90)
		(property "Reference" "R65"
			(at 3.56489 -0.141478 270)
			(unlocked yes)
			(layer "B.SilkS")
			(effects
				(font
					(size 0.7874 0.5842)
					(thickness 0.1524)
				)
				(justify mirror)
			)
		)
		(property "Value" "VAL*"
			(at -0.02032 2.13233 90)
			(unlocked yes)
			(layer "B.Fab")
			(hide yes)
			(effects
				(font
					(size 0.7874 0.5842)
					(thickness 0.1524)
				)
				(justify mirror)
			)
		)
		(property "Device Type" "RESISTOR-G155-14701-01,4.7KOHMA"
			(at -0.008382 1.210564 90)
			(unlocked yes)
			(layer "B.Fab")
			(hide yes)
			(effects
				(font
					(size 0.7874 0.5842)
					(thickness 0.1524)
				)
				(justify mirror)
			)
		)
		(property "User Part Number" "PARTNUM*"
			(at -0.02032 4.024884 90)
			(unlocked yes)
			(layer "Cmts.User")
			(hide yes)
			(effects
				(font
					(size 0.7874 0.5842)
					(thickness 0.1524)
				)
				(justify mirror)
			)
		)
		(property "Tolerance" "TOL*"
			(at -0.044704 3.05435 90)
			(unlocked yes)
			(layer "Cmts.User")
			(hide yes)
			(effects
				(font
					(size 0.7874 0.5842)
					(thickness 0.1524)
				)
				(justify mirror)
			)
		)
		(duplicate_pad_numbers_are_jumpers no)
		(fp_line
			(start 1.143 -0.5588)
			(end 1.143 0.5588)
			(stroke
				(width 0.1)
				(type default)
			)
			(layer "B.SilkS")
		)
		(fp_line
			(start -1.143 -0.5588)
			(end 1.143 -0.5588)
			(stroke
				(width 0.1)
				(type default)
			)
			(layer "B.SilkS")
		)
		(fp_line
			(start 1.143 0.5588)
			(end -1.143 0.5588)
			(stroke
				(width 0.1)
				(type default)
			)
			(layer "B.SilkS")
		)
		(fp_line
			(start -1.143 0.5588)
			(end -1.143 -0.5588)
			(stroke
				(width 0.1)
				(type default)
			)
			(layer "B.SilkS")
		)
		(fp_rect
			(start 1.143 0.5588)
			(end -1.143 -0.5588)
			(stroke
				(width 0)
				(type default)
			)
			(fill no)
			(layer "B.CrtYd")
		)
		(fp_line
			(start 0.508 -0.3048)
			(end 0.508 0.3048)
			(stroke
				(width 0.1)
				(type default)
			)
			(layer "B.Fab")
		)
		(fp_line
			(start -0.508 -0.3048)
			(end 0.508 -0.3048)
			(stroke
				(width 0.1)
				(type default)
			)
			(layer "B.Fab")
		)
		(fp_line
			(start 0.508 0.3048)
			(end -0.508 0.3048)
			(stroke
				(width 0.1)
				(type default)
			)
			(layer "B.Fab")
		)
		(fp_line
			(start -0.508 0.3048)
			(end -0.508 -0.3048)
			(stroke
				(width 0.1)
				(type default)
			)
			(layer "B.Fab")
		)
		(pad "1" smd rect
			(at 0.5334 0 270)
			(size 0.7112 0.6096)
			(layers "B.Cu" "B.Mask" "B.Paste")
			(net "XP3R3V_FPGA")
		)
		(pad "2" smd rect
			(at -0.5334 0 270)
			(size 0.7112 0.6096)
			(layers "B.Cu" "B.Mask" "B.Paste")
			(net "SHT3X_I2C_SCL")
		)
		(zone
			(layer "B.Cu")
			(hatch none 0.5)
			(connect_pads
				(clearance 0)
			)
			(min_thickness 0.25)
			(keepout
				(tracks allowed)
				(vias not_allowed)
				(pads allowed)
				(copperpour not_allowed)
				(footprints allowed)
			)
			(placement
				(enabled no)
				(sheetname "")
			)
			(fill
				(thermal_gap 0.5)
				(thermal_bridge_width 0.5)
				(island_removal_mode 0)
			)
			(polygon
				(pts
					(xy 154.457908 -49.08931) (xy 153.848308 -49.08931) (xy 153.848308 -48.93691) (xy 154.457908 -48.93691)
				)
			)
		)
	)
)
